# BASEBOARD_FAB2 (Tioga Pass) — schematic parts with pin connectivity, parts 4665–4665 of 4751; source: Cadence DE-HDL packaged netlist (pstxprt.dat, pstxnet.dat, pstchip.dat)

U5D1  SKX_EXT_B  IC  pkg BGA1  page 21  (pins 1018-1356 of 3647)
  BL12  VSS(595)  GROUND  = GND
  BL14  CD_VCC_CORE(0)  POWER  = PVCCMCP_CPU0
  BL16  CD_VSS_VCC_CORE_SENSE  POWER  = VSENSE_PVCCMCP_CPU0_SKT_VRTN
  BL18  RSVD(138)  BI  = PVCCIOMCP_CPU0
  BL20  RSVD(137)  BI  = PVCCMCP_CPU0
  BL22  VSS(593)  GROUND  = GND
  BL24  VSS(592)  GROUND  = GND
  BL26  VCCIO(87)  POWER  = PVCCIO_CPU0
  BL60  VCCIN(154)  POWER  = PVCCIN_CPU0
  BL62  VCCIN(153)  POWER  = PVCCIN_CPU0
  BL64  VSS(591)  GROUND  = GND
  BL66  VSS(590)  GROUND  = GND
  BL68  VSS(589)  GROUND  = GND
  BL70  VSS(588)  GROUND  = GND
  BL72  VSS(587)  GROUND  = GND
  BL74  VSS(586)  GROUND  = GND
  BL76  VSS(585)  GROUND  = GND
  BL78  VSS(584)  GROUND  = GND
  BL80  VSS(583)  GROUND  = GND
  BL82  VSS(582)  GROUND  = GND
  BL84  VCCIN(152)  POWER  = PVCCIN_CPU0
  BM3  PE2_TX_DP(14)  OUT  = P3E_CPU0_PE2_SS_TXP<14>
  BM5  PE2_TX_DN(15)  OUT  = P3E_CPU0_PE2_SS_TXN<15>
  BM7  PE2_RX_DP(13)  IN  = P3E_CPU0_PE2_SS_RXP<13>
  BM9  VSS(581)  GROUND  = GND
  BM11  CD_VCCP(15)  POWER  = PVCCIOMCP_CPU0
  BM13  VSS(580)  GROUND  = GND
  BM15  VSS(579)  GROUND  = GND
  BM17  RSVD(136)  BI  = PVCCIOMCP_CPU0
  BM19  RSVD(135)  BI  = PVCCMCP_CPU0
  BM21  CD_HFI1_INT_N  IN  = IRQ_HFI1_CPU0_LVT2_N
  BM23  CD_HFI1_LED_N  OUT  = LED_HFI1_CPU0_N
  BM25  VSS(577)  GROUND  = GND
  BM27  VCCIO(86)  POWER  = PVCCIO_CPU0
  BM61  VCCIN(151)  POWER  = PVCCIN_CPU0
  BM63  VCCIN(150)  POWER  = PVCCIN_CPU0
  BM65  VCCIN(149)  POWER  = PVCCIN_CPU0
  BM67  VCCIN(148)  POWER  = PVCCIN_CPU0
  BM69  VCCIN(147)  POWER  = PVCCIN_CPU0
  BM71  VCCIN(146)  POWER  = PVCCIN_CPU0
  BM73  VCCIN(145)  POWER  = PVCCIN_CPU0
  BM75  VCCIN(144)  POWER  = PVCCIN_CPU0
  BM77  VCCIN(143)  POWER  = PVCCIN_CPU0
  BM79  VCCIN(142)  POWER  = PVCCIN_CPU0
  BM81  VCCIN(141)  POWER  = PVCCIN_CPU0
  BM83  VCCIN(140)  POWER  = PVCCIN_CPU0
  BN4  PE2_TX_DP(13)  OUT  = P3E_CPU0_PE2_SS_TXP<13>
  BN6  VSS(576)  GROUND  = GND
  BN8  PE2_RX_DN(13)  IN  = P3E_CPU0_PE2_SS_RXN<13>
  BN10  VSS(575)  GROUND  = GND
  BN12  CD_VCCP(14)  POWER  = PVCCIOMCP_CPU0
  BN14  CD_VCCP(13)  POWER  = PVCCIOMCP_CPU0
  BN16  CD_VCC_CORE_SENSE  POWER  = VSENSE_PVCCMCP_CPU0_SKT_VSEN
  BN18  RSVD(134)  BI  = PVCCIOMCP_CPU0
  BN20  VSS(574)  GROUND  = GND
  BN22  CD_HFI0_I2CCLK  BI  = SMB_HFI0_CPU0_LVC2_SCL
  BN24  CD_HFI0_RESET_N  OUT  = RST_HFI0_CPU0_LVT2_N
  BN26  VSS(573)  GROUND  = GND
  BN60  VCCIN(139)  POWER  = PVCCIN_CPU0
  BN62  VCCIN(138)  POWER  = PVCCIN_CPU0
  BN64  VCCIN(137)  POWER  = PVCCIN_CPU0
  BN66  VCCIN(136)  POWER  = PVCCIN_CPU0
  BN68  VCCIN(135)  POWER  = PVCCIN_CPU0
  BN70  VCCIN(134)  POWER  = PVCCIN_CPU0
  BN72  VCCIN(133)  POWER  = PVCCIN_CPU0
  BN74  VCCIN(132)  POWER  = PVCCIN_CPU0
  BN76  VCCIN(131)  POWER  = PVCCIN_CPU0
  BN78  VCCIN(130)  POWER  = PVCCIN_CPU0
  BN80  VCCIN(129)  POWER  = PVCCIN_CPU0
  BN82  VCCIN(128)  POWER  = PVCCIN_CPU0
  BN84  VCCIN(127)  POWER  = PVCCIN_CPU0
  BP3  VSS(572)  GROUND  = GND
  BP5  PE2_TX_DN(13)  OUT  = P3E_CPU0_PE2_SS_TXN<13>
  BP7  PE2_RX_DP(11)  IN  = P3E_CPU0_PE2_SS_RXP<11>
  BP9  PE2_RX_DP(12)  IN  = P3E_CPU0_PE2_SS_RXP<12>
  BP11  CD_VCCP(12)  POWER  = PVCCIOMCP_CPU0
  BP13  CD_VCCP(11)  POWER  = PVCCIOMCP_CPU0
  BP15  CD_VCCP(10)  POWER  = PVCCIOMCP_CPU0
  BP17  RSVD(133)  BI  = PVCCIOMCP_CPU0
  BP19  CD_HFI0_INT_N  IN  = IRQ_HFI0_CPU0_LVT2_N
  BP21  RSVD(132)  BI  = PVCCMCP_CPU0
  BP23  CD_HFI0_I2CDAT  BI  = SMB_HFI0_CPU0_LVC2_SDA
  BP25  VCCIO(30)  POWER  = PVCCIO_CPU0
  BP27  VSS(571)  GROUND  = GND
  BP61  VCCIN(126)  POWER  = PVCCIN_CPU0
  BP63  VCCIN(125)  POWER  = PVCCIN_CPU0
  BP65  VCCIN(124)  POWER  = PVCCIN_CPU0
  BP67  VCCIN(123)  POWER  = PVCCIN_CPU0
  BP69  VCCIN(122)  POWER  = PVCCIN_CPU0
  BP71  VCCIN(121)  POWER  = PVCCIN_CPU0
  BP73  VCCIN(120)  POWER  = PVCCIN_CPU0
  BP75  VCCIN(119)  POWER  = PVCCIN_CPU0
  BP77  VCCIN(118)  POWER  = PVCCIN_CPU0
  BP79  VCCIN(117)  POWER  = PVCCIN_CPU0
  BP81  VCCIN(116)  POWER  = PVCCIN_CPU0
  BP83  VCCIN(115)  POWER  = PVCCIN_CPU0
  BR4  PE2_TX_DP(12)  OUT  = P3E_CPU0_PE2_SS_TXP<12>
  BR6  VSS(570)  GROUND  = GND
  BR8  PE2_RX_DN(12)  IN  = P3E_CPU0_PE2_SS_RXN<12>
  BR10  VSS(569)  GROUND  = GND
  BR12  CD_VCCP(9)  POWER  = PVCCIOMCP_CPU0
  BR14  CD_VCCP(8)  POWER  = PVCCIOMCP_CPU0
  BR16  VSS(568)  GROUND  = GND
  BR18  VSS(34)  GROUND  = GND
  BR20  CD_HFI0_MODPRST_N  IN  = FM_MODPRST_HFI0_CPU0_LVT2_N
  BR22  RSVD(131)  BI  = PVCCMCP_CPU0
  BR24  RSVD(130)  BI  = PVCCMCP_CPU0
  BR26  VSS(127)  GROUND  = GND
  BR60  VCCIN(114)  POWER  = PVCCIN_CPU0
  BR62  VCCIN(113)  POWER  = PVCCIN_CPU0
  BR64  VSS(566)  GROUND  = GND
  BR66  VSS(565)  GROUND  = GND
  BR68  VSS(564)  GROUND  = GND
  BR70  VSS(563)  GROUND  = GND
  BR72  VSS(562)  GROUND  = GND
  BR74  VSS(561)  GROUND  = GND
  BR76  VSS(560)  GROUND  = GND
  BR78  VSS(559)  GROUND  = GND
  BR80  VSS(558)  GROUND  = GND
  BR82  VSS(557)  GROUND  = GND
  BR84  VCCIN(112)  POWER  = PVCCIN_CPU0
  BT3  VSS(556)  GROUND  = GND
  BT5  VSS(555)  GROUND  = GND
  BT7  PE2_RX_DN(11)  IN  = P3E_CPU0_PE2_SS_RXN<11>
  BT9  VSS(1064)  GROUND  = GND
  BT11  CD_VCCP(7)  POWER  = PVCCIOMCP_CPU0
  BT13  CD_VCCP(6)  POWER  = PVCCIOMCP_CPU0
  BT15  CD_VCCP(5)  POWER  = PVCCIOMCP_CPU0
  BT17  CD_VCCP_SENSE(1)  POWER  = VSENSE_PVCCIOMCP_CPU0_SKT_VSEN
  BT19  CD_HFI1_MODPRST_N  IN  = FM_MODPRST_HFI1_CPU0_LVT2_N
  BT21  VSS(554)  GROUND  = GND
  BT23  VSS(553)  GROUND  = GND
  BT25  VSS(552)  GROUND  = GND
  BT27  CD_VCCIN(0)  POWER  = P1V8_MCP_CPU0
  BT61  VCCIN(111)  POWER  = PVCCIN_CPU0
  BT63  VCCIN(110)  POWER  = PVCCIN_CPU0
  BT65  VCCIN(109)  POWER  = PVCCIN_CPU0
  BT67  VCCIN(108)  POWER  = PVCCIN_CPU0
  BT69  VCCIN(107)  POWER  = PVCCIN_CPU0
  BT71  VCCIN(106)  POWER  = PVCCIN_CPU0
  BT73  VCCIN(105)  POWER  = PVCCIN_CPU0
  BT75  VCCIN(104)  POWER  = PVCCIN_CPU0
  BT77  VCCIN(103)  POWER  = PVCCIN_CPU0
  BT79  VCCIN(102)  POWER  = PVCCIN_CPU0
  BT81  VCCIN(101)  POWER  = PVCCIN_CPU0
  BT83  VCCIN(100)  POWER  = PVCCIN_CPU0
  BU4  PE2_TX_DN(12)  OUT  = P3E_CPU0_PE2_SS_TXN<12>
  BU6  PE2_RX_DP(10)  IN  = P3E_CPU0_PE2_SS_RXP<10>
  BU8  VSS(551)  GROUND  = GND
  BU10  VSS(549)  GROUND  = GND
  BU12  CD_VCCP(4)  POWER  = PVCCIOMCP_CPU0
  BU14  CD_VCCP(3)  POWER  = PVCCIOMCP_CPU0
  BU16  CD_VCCP_SENSE(0)  POWER  = VSENSE_PVCCIOMCP_CPU0_SKT_VRTN
  BU18  RSVD(129)  BI  = PVCCIOMCP_CPU0
  BU20  RSVD(128)  BI  = PVCCMCP_CPU0
  BU22  RSVD(127)  BI  = PVCCMCP_CPU0
  BU24  CD_PE_REFCLK_DN  IN  = CLK_100M_CPU0_PE_REFCLK_DN
  BU26  CD_VCCIN(1)  POWER  = P1V8_MCP_CPU0
  BU60  VCCIN(99)  POWER  = PVCCIN_CPU0
  BU62  VCCIN(98)  POWER  = PVCCIN_CPU0
  BU64  VCCIN(97)  POWER  = PVCCIN_CPU0
  BU66  VCCIN(96)  POWER  = PVCCIN_CPU0
  BU68  VCCIN(95)  POWER  = PVCCIN_CPU0
  BU70  VCCIN(94)  POWER  = PVCCIN_CPU0
  BU72  VCCIN(93)  POWER  = PVCCIN_CPU0
  BU74  VCCIN(92)  POWER  = PVCCIN_CPU0
  BU76  VCCIN(91)  POWER  = PVCCIN_CPU0
  BU78  VCCIN(90)  POWER  = PVCCIN_CPU0
  BU80  VCCIN(89)  POWER  = PVCCIN_CPU0
  BU82  VCCIN(88)  POWER  = PVCCIN_CPU0
  BU84  VCCIN(87)  POWER  = PVCCIN_CPU0
  BV3  PE2_TX_DP(11)  OUT  = P3E_CPU0_PE2_SS_TXP<11>
  BV5  VSS(550)  GROUND  = GND
  BV7  PE2_RX_DN(10)  IN  = P3E_CPU0_PE2_SS_RXN<10>
  BV9  PE2_RX_DP(8)  IN  = P3E_CPU0_PE2_SS_RXP<8>
  BV11  CD_VCCP(2)  POWER  = PVCCIOMCP_CPU0
  BV13  CD_VCCP(1)  POWER  = PVCCIOMCP_CPU0
  BV15  CD_VCCP(0)  POWER  = PVCCIOMCP_CPU0
  BV17  VSS(548)  GROUND  = GND
  BV19  RSVD(126)  BI  = PVCCMCP_CPU0
  BV21  RSVD(125)  BI  = PVCCMCP_CPU0
  BV23  RSVD(124)  BI  = TP_CPU0_RSVD_124
  BV25  VSS(547)  GROUND  = GND
  BV27  CD_VCCIN(2)  POWER  = P1V8_MCP_CPU0
  BV61  VCCIN(86)  POWER  = PVCCIN_CPU0
  BV63  VCCIN(85)  POWER  = PVCCIN_CPU0
  BV65  VCCIN(84)  POWER  = PVCCIN_CPU0
  BV67  VCCIN(83)  POWER  = PVCCIN_CPU0
  BV69  VCCIN(82)  POWER  = PVCCIN_CPU0
  BV71  VCCIN(81)  POWER  = PVCCIN_CPU0
  BV73  VCCIN(80)  POWER  = PVCCIN_CPU0
  BV75  VCCIN(79)  POWER  = PVCCIN_CPU0
  BV77  VCCIN(78)  POWER  = PVCCIN_CPU0
  BV79  VCCIN(77)  POWER  = PVCCIN_CPU0
  BV81  VCCIN(76)  POWER  = PVCCIN_CPU0
  BV83  VCCIN(75)  POWER  = PVCCIN_CPU0
  BW4  PE2_TX_DN(11)  OUT  = P3E_CPU0_PE2_SS_TXN<11>
  BW6  VSS(546)  GROUND  = GND
  BW8  PE2_RX_DP(9)  IN  = P3E_CPU0_PE2_SS_RXP<9>
  BW10  RSVD(123)  BI  = TP_CPU0_RSVD_123
  BW12  VSS(544)  GROUND  = GND
  BW14  VSS(543)  GROUND  = GND
  BW16  VSS(542)  GROUND  = GND
  BW18  VSS(541)  GROUND  = GND
  BW20  RSVD(122)  BI  = PVCCMCP_CPU0
  BW22  RSVD(121)  BI  = TP_CPU0_RSVD_121
  BW24  CD_PE_REFCLK_DP  IN  = CLK_100M_CPU0_PE_REFCLK_DP
  BW26  VSS(540)  GROUND  = GND
  BW60  VCCIN(74)  POWER  = PVCCIN_CPU0
  BW62  VCCIN(73)  POWER  = PVCCIN_CPU0
  BW64  VCCIN(72)  POWER  = PVCCIN_CPU0
  BW66  VCCIN(71)  POWER  = PVCCIN_CPU0
  BW68  VCCIN(70)  POWER  = PVCCIN_CPU0
  BW70  VCCIN(69)  POWER  = PVCCIN_CPU0
  BW72  VSS(539)  GROUND  = GND
  BW74  VSS(538)  GROUND  = GND
  BW76  VSS(537)  GROUND  = GND
  BW78  VSS(536)  GROUND  = GND
  BW80  VSS(535)  GROUND  = GND
  BW82  VSS(534)  GROUND  = GND
  BW84  VCCIN(68)  POWER  = PVCCIN_CPU0
  BY3  PE2_TX_DP(9)  OUT  = P3E_CPU0_PE2_SS_TXP<9>
  BY5  PE2_TX_DP(10)  OUT  = P3E_CPU0_PE2_SS_TXP<10>
  BY7  PE2_RX_DN(9)  IN  = P3E_CPU0_PE2_SS_RXN<9>
  BY9  PE2_RX_DN(8)  IN  = P3E_CPU0_PE2_SS_RXN<8>
  BY11  VSS(533)  GROUND  = GND
  BY13  VSS(532)  GROUND  = GND
  BY15  UPI2_RX_DP(18)  IN  = GND
  BY17  UPI2_RX_DN(19)  IN  = GND
  BY19  RSVD(120)  BI  = PVCCMCP_CPU0
  BY21  CD_TDI  IN  = JTAG_MCP_CPU0_TDI
  BY23  VSS(531)  GROUND  = GND
  BY25  RSVD(119)  BI  = TP_CPU0_RSVD_119
  BY27  CD_VCCIN(3)  POWER  = P1V8_MCP_CPU0
  BY61  VCCIN(67)  POWER  = PVCCIN_CPU0
  BY63  VSS(530)  GROUND  = GND
  BY65  VSS(529)  GROUND  = GND
  BY67  VSS(528)  GROUND  = GND
  BY69  VSS(527)  GROUND  = GND
  BY71  VSS(526)  GROUND  = GND
  BY73  VCCIN(66)  POWER  = PVCCIN_CPU0
  BY75  VCCIN(65)  POWER  = PVCCIN_CPU0
  BY77  VCCIN(64)  POWER  = PVCCIN_CPU0
  BY79  VCCIN(63)  POWER  = PVCCIN_CPU0
  BY81  VCCIN(62)  POWER  = PVCCIN_CPU0
  BY83  VCCIN(61)  POWER  = PVCCIN_CPU0
  C4  VSS(1248)  GROUND  = GND
  C6  RSVD(291)  BI  = TP_CPU0_RSVD_291
  C8  VSS(1175)  GROUND  = GND
  C10  VSS(1174)  GROUND  = GND
  C12  VSS(1173)  GROUND  = GND
  C14  VSS(1172)  GROUND  = GND
  C16  VSS(1171)  GROUND  = GND
  C18  RSVD(290)  BI  = TP_CPU0_RSVD_290
  C24  RSVD(289)  BI  = TP_CPU0_RSVD_289
  C26  DDR1_DQ(50)  BI  = M_B_DQ<50>
  C28  DDR1_DQS_DP(15)  BI  = M_B_DQS_DP<15>
  C30  DDR1_DQ(48)  BI  = M_B_DQ<48>
  C32  DDR1_DQ(42)  BI  = M_B_DQ<42>
  C34  DDR1_DQS_DP(14)  BI  = M_B_DQS_DP<14>
  C36  DDR1_DQ(40)  BI  = M_B_DQ<40>
  C38  DDR0_DQ(34)  BI  = M_A_DQ<34>
  C40  DDR0_DQS_DP(13)  BI  = M_A_DQS_DP<13>
  C42  DDR0_DQ(32)  BI  = M_A_DQ<32>
  C46  VCCD012(50)  POWER  = PVDDQ_ABC
  C48  DDR0_ODT(1)  OUT  = M_A_ODT<1>
  C50  DDR0_ODT(0)  OUT  = M_A_ODT<0>
  C52  DDR0_BA(0)  OUT  = M_A_BA<0>
  C54  DDR0_CLK_DN(1)  OUT  = M_A_CLK_DN<1>
  C56  DDR0_CLK_DN(3)  OUT  = M_A_CLK_DN<3>
  C58  DDR0_MA(3)  OUT  = M_A_MA<3>
  C60  DDR0_MA(8)  OUT  = M_A_MA<8>
  C62  DDR0_CKE(0)  OUT  = M_A_CKE<0>
  C64  DDR0_CKE(1)  OUT  = M_A_CKE<1>
  C72  DDR1_DQ(30)  BI  = M_B_DQ<30>
  C74  DDR1_DQ(25)  BI  = M_B_DQ<25>
  C76  VSS(1170)  GROUND  = GND
  C78  VSS(1169)  GROUND  = GND
  C80  VSS(1247)  GROUND  = GND
  C82  RSVD(288)  BI  = TP_CPU0_RSVD_288
  CA2  VSS(525)  GROUND  = GND
  CA4  PE2_TX_DN(10)  OUT  = P3E_CPU0_PE2_SS_TXN<10>
  CA6  VSS(524)  GROUND  = GND
  CA8  VSS(523)  GROUND  = GND
  CA10  VSS(522)  GROUND  = GND
  CA12  UPI2_TX_DP(19)  OUT  = TP_CPU0_UPI2_RSVD_DP21
  CA14  VSS(521)  GROUND  = GND
  CA16  UPI2_RX_DP(19)  IN  = GND
  CA18  VSS(520)  GROUND  = GND
  CA20  VSS(125)  GROUND  = GND
  CA22  RSVD(118)  BI  = PVCCMCP_CPU0
  CA24  RSVD(117)  BI  = TP_CPU0_RSVD_117
  CA26  VSS(519)  GROUND  = GND
  CA60  VCCIN(60)  POWER  = PVCCIN_CPU0
  CA62  VCCIN(59)  POWER  = PVCCIN_CPU0
  CA64  VSS(518)  GROUND  = GND
  CA66  VSS(517)  GROUND  = GND
  CA68  VSS(516)  GROUND  = GND
  CA70  VSS(515)  GROUND  = GND
  CA72  VCCIN(58)  POWER  = PVCCIN_CPU0
  CA74  VCCIN(57)  POWER  = PVCCIN_CPU0
  CA76  VCCIN(56)  POWER  = PVCCIN_CPU0
  CA78  VCCIN(55)  POWER  = PVCCIN_CPU0
  CA80  VCCIN(54)  POWER  = PVCCIN_CPU0
  CA82  VCCIN(53)  POWER  = PVCCIN_CPU0
  CA84  VCCIN(52)  POWER  = PVCCIN_CPU0
  CB3  PE2_TX_DN(9)  OUT  = P3E_CPU0_PE2_SS_TXN<9>
  CB5  RSVD(113)  BI  = TP_CPU0_RSVD_113
  CB7  VSS(514)  GROUND  = GND
  CB9  VSS(513)  GROUND  = GND
  CB11  UPI2_TX_DP(18)  OUT  = TP_CPU0_UPI2_RSVD_DN20
  CB13  VCCIO(29)  POWER  = PVCCIO_CPU0
  CB15  UPI2_RX_DN(18)  IN  = GND
  CB17  VCCIO(28)  POWER  = PVCCIO_CPU0
  CB19  RSVD(116)  BI  = PVCCMCP_CPU0
  CB21  RSVD(115)  BI  = PVCCMCP_CPU0
  CB23  CD_TCLK  IN  = JTAG_MCP_TCK
  CB25  RSVD(114)  BI  = TP_CPU0_RSVD_114
  CB27  VSS(512)  GROUND  = GND
  CB61  VCCIN(51)  POWER  = PVCCIN_CPU0
  CB63  VSS(511)  GROUND  = GND
  CB65  VCCSA(25)  POWER  = PVSA_CPU0
  CB67  VCCSA(24)  POWER  = PVSA_CPU0
  CB69  VCCSA(23)  POWER  = PVSA_CPU0
  CB71  VSS(510)  GROUND  = GND
  CB73  VCCIN(50)  POWER  = PVCCIN_CPU0
  CB75  VCCIN(49)  POWER  = PVCCIN_CPU0
  CB77  VCCIN(48)  POWER  = PVCCIN_CPU0
  CB79  VCCIN(47)  POWER  = PVCCIN_CPU0
  CB81  VCCIN(46)  POWER  = PVCCIN_CPU0
  CB83  VCCIN(45)  POWER  = PVCCIN_CPU0
  CC2  PE2_TX_DN(8)  OUT  = P3E_CPU0_PE2_SS_TXN<8>
  CC4  VSS(509)  GROUND  = GND
  CC6  RSVD(111)  BI  = TP_CPU0_RSVD_111
  CC8  PE2_RX_DP(7)  IN  = P3E_CPU0_PE2_SS_RXP<7>
  CC10  UPI2_TX_DN(18)  OUT  = TP_CPU0_UPI2_RSVD_DM21
  CC12  UPI2_TX_DN(19)  OUT  = TP_CPU0_UPI2_RSVD_DT21
  CC14  UPI2_RX_DP(16)  IN  = GND
  CC16  VSS(508)  GROUND  = GND
